(kicad_pcb
	(version 20260206)
	(generator "pcbnew")
	(generator_version "10.0")
	(general
		(thickness 1.6)
		(legacy_teardrops no)
	)
	(paper "A4")
	(title_block
		(title "04192023_DAF0TMB3IC0_F0TG_MB_C_brd_V02_OCP.brd")
		(comment 1 "Grand Teton / footprints 248-254 of 8354")
	)
	(layers
		(0 "F.Cu" signal "TOP")
		(4 "In1.Cu" signal "GND")
		(6 "In2.Cu" signal "IN1")
		(8 "In3.Cu" signal "GND1")
		(10 "In4.Cu" signal "IN2")
		(12 "In5.Cu" signal "GND2")
		(14 "In6.Cu" signal "IN3")
		(16 "In7.Cu" signal "GND3")
		(18 "In8.Cu" signal "VCC")
		(20 "In9.Cu" signal "VCC1")
		(22 "In10.Cu" signal "GND4")
		(24 "In11.Cu" signal "IN4")
		(26 "In12.Cu" signal "GND5")
		(28 "In13.Cu" signal "IN5")
		(30 "In14.Cu" signal "GND6")
		(32 "In15.Cu" signal "IN6")
		(34 "In16.Cu" signal "GND7")
		(2 "B.Cu" signal "BOTTOM")
		(9 "F.Adhes" user "F.Adhesive")
		(11 "B.Adhes" user "B.Adhesive")
		(13 "F.Paste" user "Package Geometry/Pastemask Top")
		(15 "B.Paste" user "Package Geometry/Pastemask Bottom")
		(5 "F.SilkS" user "Ref Des/Silkscreen Top")
		(7 "B.SilkS" user "Ref Des/Silkscreen Bottom")
		(1 "F.Mask" user "Board Geometry/Soldermask Top")
		(3 "B.Mask" user "Board Geometry/Soldermask Bottom")
		(17 "Dwgs.User" user "User.Drawings")
		(19 "Cmts.User" user "User.Comments")
		(21 "Eco1.User" user "User.Eco1")
		(23 "Eco2.User" user "User.Eco2")
		(25 "Edge.Cuts" user "Board Geometry/Outline")
		(27 "Margin" user)
		(31 "F.CrtYd" user "Package Geometry/Place Bound Top")
		(29 "B.CrtYd" user "Package Geometry/Place Bound Bottom")
		(35 "F.Fab" user "Ref Des/Assembly Top")
		(33 "B.Fab" user "Ref Des/Assembly Bottom")
	)
	(footprint ""
		(layer "F.Cu")
		(at 97.652078 -404.593044 90)
		(property "Reference" "C1069"
			(at 0 0 90)
			(layer "F.SilkS")
			(hide yes)
			(effects
				(font
					(size 1.27 1.27)
				)
			)
		)
		(property "Value" ""
			(at 0 0 90)
			(layer "F.Fab")
			(effects
				(font
					(size 1.27 1.27)
				)
			)
		)
		(duplicate_pad_numbers_are_jumpers no)
		(fp_line
			(start 0.299974 -0.150114)
			(end 0.299974 0.150114)
			(stroke
				(width 0.1)
				(type default)
			)
			(layer "F.Fab")
		)
		(fp_line
			(start -0.299974 -0.150114)
			(end 0.299974 -0.150114)
			(stroke
				(width 0.1)
				(type default)
			)
			(layer "F.Fab")
		)
		(fp_line
			(start 0.299974 0.150114)
			(end -0.299974 0.150114)
			(stroke
				(width 0.1)
				(type default)
			)
			(layer "F.Fab")
		)
		(fp_line
			(start -0.299974 0.150114)
			(end -0.299974 -0.150114)
			(stroke
				(width 0.1)
				(type default)
			)
			(layer "F.Fab")
		)
		(pad "1" smd rect
			(at -0.2667 0 90)
			(size 0.3048 0.381)
			(layers "F.Cu" "F.Mask" "F.Paste")
			(net "P3V3_AUX")
		)
		(pad "2" smd rect
			(at 0.2667 0 90)
			(size 0.3048 0.381)
			(layers "F.Cu" "F.Mask" "F.Paste")
			(net "GND")
		)
	)
	(footprint ""
		(layer "F.Cu")
		(at 257.85953 -54.463442)
		(property "Reference" "PC2202"
			(at 0 0 0)
			(layer "F.SilkS")
			(hide yes)
			(effects
				(font
					(size 1.27 1.27)
				)
			)
		)
		(property "Value" ""
			(at 0 0 0)
			(layer "F.Fab")
			(effects
				(font
					(size 1.27 1.27)
				)
			)
		)
		(duplicate_pad_numbers_are_jumpers no)
		(fp_line
			(start -0.7874 -0.4064)
			(end 0.7874 -0.4064)
			(stroke
				(width 0.1524)
				(type default)
			)
			(layer "F.SilkS")
		)
		(fp_line
			(start -0.7874 0.4064)
			(end -0.7874 -0.4064)
			(stroke
				(width 0.1524)
				(type default)
			)
			(layer "F.SilkS")
		)
		(fp_line
			(start 0.7874 -0.4064)
			(end 0.7874 0.4064)
			(stroke
				(width 0.1524)
				(type default)
			)
			(layer "F.SilkS")
		)
		(fp_line
			(start 0.7874 0.4064)
			(end -0.7874 0.4064)
			(stroke
				(width 0.1524)
				(type default)
			)
			(layer "F.SilkS")
		)
		(fp_line
			(start -0.67945 -0.305054)
			(end -0.12065 -0.305054)
			(stroke
				(width 0.1)
				(type default)
			)
			(layer "F.Fab")
		)
		(fp_line
			(start -0.67945 0.3048)
			(end -0.67945 -0.305054)
			(stroke
				(width 0.1)
				(type default)
			)
			(layer "F.Fab")
		)
		(fp_line
			(start -0.12065 -0.305054)
			(end -0.12065 -0.2794)
			(stroke
				(width 0.1)
				(type default)
			)
			(layer "F.Fab")
		)
		(fp_line
			(start -0.12065 -0.2794)
			(end 0.12065 -0.2794)
			(stroke
				(width 0.1)
				(type default)
			)
			(layer "F.Fab")
		)
		(fp_line
			(start -0.12065 0.2794)
			(end -0.12065 0.3048)
			(stroke
				(width 0.1)
				(type default)
			)
			(layer "F.Fab")
		)
		(fp_line
			(start -0.12065 0.3048)
			(end -0.67945 0.3048)
			(stroke
				(width 0.1)
				(type default)
			)
			(layer "F.Fab")
		)
		(fp_line
			(start 0.120396 0.2794)
			(end -0.12065 0.2794)
			(stroke
				(width 0.1)
				(type default)
			)
			(layer "F.Fab")
		)
		(fp_line
			(start 0.120396 0.3048)
			(end 0.120396 0.2794)
			(stroke
				(width 0.1)
				(type default)
			)
			(layer "F.Fab")
		)
		(fp_line
			(start 0.12065 -0.3048)
			(end 0.67945 -0.3048)
			(stroke
				(width 0.1)
				(type default)
			)
			(layer "F.Fab")
		)
		(fp_line
			(start 0.12065 -0.2794)
			(end 0.12065 -0.3048)
			(stroke
				(width 0.1)
				(type default)
			)
			(layer "F.Fab")
		)
		(fp_line
			(start 0.67945 -0.3048)
			(end 0.67945 0.3048)
			(stroke
				(width 0.1)
				(type default)
			)
			(layer "F.Fab")
		)
		(fp_line
			(start 0.67945 0.3048)
			(end 0.120396 0.3048)
			(stroke
				(width 0.1)
				(type default)
			)
			(layer "F.Fab")
		)
		(pad "1" smd circle
			(at -0.40005 0)
			(size 0 0)
			(layers "F.Cu" "F.Mask" "F.Paste")
			(net "P12V_E1S_IMON_0")
		)
		(pad "2" smd circle
			(at 0.40005 0)
			(size 0 0)
			(layers "F.Cu" "F.Mask" "F.Paste")
			(net "GND")
		)
	)
	(footprint ""
		(layer "F.Cu")
		(at 329.360022 -37.017706)
		(property "Reference" "C1757"
			(at 0 0 0)
			(layer "F.SilkS")
			(hide yes)
			(effects
				(font
					(size 1.27 1.27)
				)
			)
		)
		(property "Value" ""
			(at 0 0 0)
			(layer "F.Fab")
			(effects
				(font
					(size 1.27 1.27)
				)
			)
		)
		(duplicate_pad_numbers_are_jumpers no)
		(fp_line
			(start -0.7874 -0.4064)
			(end 0.7874 -0.4064)
			(stroke
				(width 0.1524)
				(type default)
			)
			(layer "F.SilkS")
		)
		(fp_line
			(start -0.7874 0.4064)
			(end -0.7874 -0.4064)
			(stroke
				(width 0.1524)
				(type default)
			)
			(layer "F.SilkS")
		)
		(fp_line
			(start 0.7874 -0.4064)
			(end 0.7874 0.4064)
			(stroke
				(width 0.1524)
				(type default)
			)
			(layer "F.SilkS")
		)
		(fp_line
			(start 0.7874 0.4064)
			(end -0.7874 0.4064)
			(stroke
				(width 0.1524)
				(type default)
			)
			(layer "F.SilkS")
		)
		(fp_line
			(start -0.67945 -0.305054)
			(end -0.12065 -0.305054)
			(stroke
				(width 0.1)
				(type default)
			)
			(layer "F.Fab")
		)
		(fp_line
			(start -0.67945 0.3048)
			(end -0.67945 -0.305054)
			(stroke
				(width 0.1)
				(type default)
			)
			(layer "F.Fab")
		)
		(fp_line
			(start -0.12065 -0.305054)
			(end -0.12065 -0.2794)
			(stroke
				(width 0.1)
				(type default)
			)
			(layer "F.Fab")
		)
		(fp_line
			(start -0.12065 -0.2794)
			(end 0.12065 -0.2794)
			(stroke
				(width 0.1)
				(type default)
			)
			(layer "F.Fab")
		)
		(fp_line
			(start -0.12065 0.2794)
			(end -0.12065 0.3048)
			(stroke
				(width 0.1)
				(type default)
			)
			(layer "F.Fab")
		)
		(fp_line
			(start -0.12065 0.3048)
			(end -0.67945 0.3048)
			(stroke
				(width 0.1)
				(type default)
			)
			(layer "F.Fab")
		)
		(fp_line
			(start 0.120396 0.2794)
			(end -0.12065 0.2794)
			(stroke
				(width 0.1)
				(type default)
			)
			(layer "F.Fab")
		)
		(fp_line
			(start 0.120396 0.3048)
			(end 0.120396 0.2794)
			(stroke
				(width 0.1)
				(type default)
			)
			(layer "F.Fab")
		)
		(fp_line
			(start 0.12065 -0.3048)
			(end 0.67945 -0.3048)
			(stroke
				(width 0.1)
				(type default)
			)
			(layer "F.Fab")
		)
		(fp_line
			(start 0.12065 -0.2794)
			(end 0.12065 -0.3048)
			(stroke
				(width 0.1)
				(type default)
			)
			(layer "F.Fab")
		)
		(fp_line
			(start 0.67945 -0.3048)
			(end 0.67945 0.3048)
			(stroke
				(width 0.1)
				(type default)
			)
			(layer "F.Fab")
		)
		(fp_line
			(start 0.67945 0.3048)
			(end 0.120396 0.3048)
			(stroke
				(width 0.1)
				(type default)
			)
			(layer "F.Fab")
		)
		(pad "1" smd circle
			(at -0.40005 0)
			(size 0 0)
			(layers "F.Cu" "F.Mask" "F.Paste")
			(net "P3V3_MAX11617_VDD")
		)
		(pad "2" smd circle
			(at 0.40005 0)
			(size 0 0)
			(layers "F.Cu" "F.Mask" "F.Paste")
			(net "GND")
		)
	)
	(footprint ""
		(layer "F.Cu")
		(at 384.465576 -54.56555 -90)
		(property "Reference" "R1626"
			(at 0 0 270)
			(layer "F.SilkS")
			(hide yes)
			(effects
				(font
					(size 1.27 1.27)
				)
			)
		)
		(property "Value" ""
			(at 0 0 270)
			(layer "F.Fab")
			(effects
				(font
					(size 1.27 1.27)
				)
			)
		)
		(duplicate_pad_numbers_are_jumpers no)
		(fp_line
			(start -0.7874 0.4064)
			(end -0.7874 -0.4064)
			(stroke
				(width 0.1524)
				(type default)
			)
			(layer "F.SilkS")
		)
		(fp_line
			(start 0.7874 0.4064)
			(end -0.7874 0.4064)
			(stroke
				(width 0.1524)
				(type default)
			)
			(layer "F.SilkS")
		)
		(fp_line
			(start -0.7874 -0.4064)
			(end 0.7874 -0.4064)
			(stroke
				(width 0.1524)
				(type default)
			)
			(layer "F.SilkS")
		)
		(fp_line
			(start 0.7874 -0.4064)
			(end 0.7874 0.4064)
			(stroke
				(width 0.1524)
				(type default)
			)
			(layer "F.SilkS")
		)
		(fp_line
			(start -0.67945 0.3048)
			(end -0.67945 -0.305054)
			(stroke
				(width 0.1)
				(type default)
			)
			(layer "F.Fab")
		)
		(fp_line
			(start -0.12065 0.3048)
			(end -0.67945 0.3048)
			(stroke
				(width 0.1)
				(type default)
			)
			(layer "F.Fab")
		)
		(fp_line
			(start 0.120396 0.3048)
			(end 0.120396 0.2794)
			(stroke
				(width 0.1)
				(type default)
			)
			(layer "F.Fab")
		)
		(fp_line
			(start 0.67945 0.3048)
			(end 0.120396 0.3048)
			(stroke
				(width 0.1)
				(type default)
			)
			(layer "F.Fab")
		)
		(fp_line
			(start -0.12065 0.2794)
			(end -0.12065 0.3048)
			(stroke
				(width 0.1)
				(type default)
			)
			(layer "F.Fab")
		)
		(fp_line
			(start 0.120396 0.2794)
			(end -0.12065 0.2794)
			(stroke
				(width 0.1)
				(type default)
			)
			(layer "F.Fab")
		)
		(fp_line
			(start -0.12065 -0.2794)
			(end 0.12065 -0.2794)
			(stroke
				(width 0.1)
				(type default)
			)
			(layer "F.Fab")
		)
		(fp_line
			(start 0.12065 -0.2794)
			(end 0.12065 -0.3048)
			(stroke
				(width 0.1)
				(type default)
			)
			(layer "F.Fab")
		)
		(fp_line
			(start 0.12065 -0.3048)
			(end 0.67945 -0.3048)
			(stroke
				(width 0.1)
				(type default)
			)
			(layer "F.Fab")
		)
		(fp_line
			(start 0.67945 -0.3048)
			(end 0.67945 0.3048)
			(stroke
				(width 0.1)
				(type default)
			)
			(layer "F.Fab")
		)
		(fp_line
			(start -0.67945 -0.305054)
			(end -0.12065 -0.305054)
			(stroke
				(width 0.1)
				(type default)
			)
			(layer "F.Fab")
		)
		(fp_line
			(start -0.12065 -0.305054)
			(end -0.12065 -0.2794)
			(stroke
				(width 0.1)
				(type default)
			)
			(layer "F.Fab")
		)
		(pad "1" smd circle
			(at -0.40005 0 270)
			(size 0 0)
			(layers "F.Cu" "F.Mask" "F.Paste")
			(net "PVDD18_S5_P0")
		)
		(pad "2" smd circle
			(at 0.40005 0 270)
			(size 0 0)
			(layers "F.Cu" "F.Mask" "F.Paste")
			(net "HDT_HDR_TMS")
		)
	)
	(footprint ""
		(layer "F.Cu")
		(at 279.56637 -351.100644)
		(property "Reference" "PC177_3"
			(at 0 0 0)
			(layer "F.SilkS")
			(hide yes)
			(effects
				(font
					(size 1.27 1.27)
				)
			)
		)
		(property "Value" ""
			(at 0 0 0)
			(layer "F.Fab")
			(effects
				(font
					(size 1.27 1.27)
				)
			)
		)
		(duplicate_pad_numbers_are_jumpers no)
		(fp_line
			(start -0.7874 -0.4064)
			(end 0.7874 -0.4064)
			(stroke
				(width 0.1524)
				(type default)
			)
			(layer "F.SilkS")
		)
		(fp_line
			(start -0.7874 0.4064)
			(end -0.7874 -0.4064)
			(stroke
				(width 0.1524)
				(type default)
			)
			(layer "F.SilkS")
		)
		(fp_line
			(start 0.7874 -0.4064)
			(end 0.7874 0.4064)
			(stroke
				(width 0.1524)
				(type default)
			)
			(layer "F.SilkS")
		)
		(fp_line
			(start 0.7874 0.4064)
			(end -0.7874 0.4064)
			(stroke
				(width 0.1524)
				(type default)
			)
			(layer "F.SilkS")
		)
		(fp_line
			(start -0.67945 -0.305054)
			(end -0.12065 -0.305054)
			(stroke
				(width 0.1)
				(type default)
			)
			(layer "F.Fab")
		)
		(fp_line
			(start -0.67945 0.3048)
			(end -0.67945 -0.305054)
			(stroke
				(width 0.1)
				(type default)
			)
			(layer "F.Fab")
		)
		(fp_line
			(start -0.12065 -0.305054)
			(end -0.12065 -0.2794)
			(stroke
				(width 0.1)
				(type default)
			)
			(layer "F.Fab")
		)
		(fp_line
			(start -0.12065 -0.2794)
			(end 0.12065 -0.2794)
			(stroke
				(width 0.1)
				(type default)
			)
			(layer "F.Fab")
		)
		(fp_line
			(start -0.12065 0.2794)
			(end -0.12065 0.3048)
			(stroke
				(width 0.1)
				(type default)
			)
			(layer "F.Fab")
		)
		(fp_line
			(start -0.12065 0.3048)
			(end -0.67945 0.3048)
			(stroke
				(width 0.1)
				(type default)
			)
			(layer "F.Fab")
		)
		(fp_line
			(start 0.120396 0.2794)
			(end -0.12065 0.2794)
			(stroke
				(width 0.1)
				(type default)
			)
			(layer "F.Fab")
		)
		(fp_line
			(start 0.120396 0.3048)
			(end 0.120396 0.2794)
			(stroke
				(width 0.1)
				(type default)
			)
			(layer "F.Fab")
		)
		(fp_line
			(start 0.12065 -0.3048)
			(end 0.67945 -0.3048)
			(stroke
				(width 0.1)
				(type default)
			)
			(layer "F.Fab")
		)
		(fp_line
			(start 0.12065 -0.2794)
			(end 0.12065 -0.3048)
			(stroke
				(width 0.1)
				(type default)
			)
			(layer "F.Fab")
		)
		(fp_line
			(start 0.67945 -0.3048)
			(end 0.67945 0.3048)
			(stroke
				(width 0.1)
				(type default)
			)
			(layer "F.Fab")
		)
		(fp_line
			(start 0.67945 0.3048)
			(end 0.120396 0.3048)
			(stroke
				(width 0.1)
				(type default)
			)
			(layer "F.Fab")
		)
		(pad "1" smd circle
			(at -0.40005 0)
			(size 0 0)
			(layers "F.Cu" "F.Mask" "F.Paste")
			(net "SW_P12V_AUX_PVDDIO_P0_FLT")
		)
		(pad "2" smd circle
			(at 0.40005 0)
			(size 0 0)
			(layers "F.Cu" "F.Mask" "F.Paste")
			(net "GND")
		)
	)
	(footprint ""
		(layer "F.Cu")
		(at 178.71694 -400.436842 180)
		(property "Reference" "PC2103"
			(at 0 0 180)
			(layer "F.SilkS")
			(hide yes)
			(effects
				(font
					(size 1.27 1.27)
				)
			)
		)
		(property "Value" ""
			(at 0 0 180)
			(layer "F.Fab")
			(effects
				(font
					(size 1.27 1.27)
				)
			)
		)
		(duplicate_pad_numbers_are_jumpers no)
		(fp_line
			(start 0.7874 0.4064)
			(end -0.7874 0.4064)
			(stroke
				(width 0.1524)
				(type default)
			)
			(layer "F.SilkS")
		)
		(fp_line
			(start 0.7874 -0.4064)
			(end 0.7874 0.4064)
			(stroke
				(width 0.1524)
				(type default)
			)
			(layer "F.SilkS")
		)
		(fp_line
			(start -0.7874 0.4064)
			(end -0.7874 -0.4064)
			(stroke
				(width 0.1524)
				(type default)
			)
			(layer "F.SilkS")
		)
		(fp_line
			(start -0.7874 -0.4064)
			(end 0.7874 -0.4064)
			(stroke
				(width 0.1524)
				(type default)
			)
			(layer "F.SilkS")
		)
		(fp_line
			(start 0.67945 0.3048)
			(end 0.120396 0.3048)
			(stroke
				(width 0.1)
				(type default)
			)
			(layer "F.Fab")
		)
		(fp_line
			(start 0.67945 -0.3048)
			(end 0.67945 0.3048)
			(stroke
				(width 0.1)
				(type default)
			)
			(layer "F.Fab")
		)
		(fp_line
			(start 0.12065 -0.2794)
			(end 0.12065 -0.3048)
			(stroke
				(width 0.1)
				(type default)
			)
			(layer "F.Fab")
		)
		(fp_line
			(start 0.12065 -0.3048)
			(end 0.67945 -0.3048)
			(stroke
				(width 0.1)
				(type default)
			)
			(layer "F.Fab")
		)
		(fp_line
			(start 0.120396 0.3048)
			(end 0.120396 0.2794)
			(stroke
				(width 0.1)
				(type default)
			)
			(layer "F.Fab")
		)
		(fp_line
			(start 0.120396 0.2794)
			(end -0.12065 0.2794)
			(stroke
				(width 0.1)
				(type default)
			)
			(layer "F.Fab")
		)
		(fp_line
			(start -0.12065 0.3048)
			(end -0.67945 0.3048)
			(stroke
				(width 0.1)
				(type default)
			)
			(layer "F.Fab")
		)
		(fp_line
			(start -0.12065 0.2794)
			(end -0.12065 0.3048)
			(stroke
				(width 0.1)
				(type default)
			)
			(layer "F.Fab")
		)
		(fp_line
			(start -0.12065 -0.2794)
			(end 0.12065 -0.2794)
			(stroke
				(width 0.1)
				(type default)
			)
			(layer "F.Fab")
		)
		(fp_line
			(start -0.12065 -0.305054)
			(end -0.12065 -0.2794)
			(stroke
				(width 0.1)
				(type default)
			)
			(layer "F.Fab")
		)
		(fp_line
			(start -0.67945 0.3048)
			(end -0.67945 -0.305054)
			(stroke
				(width 0.1)
				(type default)
			)
			(layer "F.Fab")
		)
		(fp_line
			(start -0.67945 -0.305054)
			(end -0.12065 -0.305054)
			(stroke
				(width 0.1)
				(type default)
			)
			(layer "F.Fab")
		)
		(pad "1" smd circle
			(at -0.40005 0 180)
			(size 0 0)
			(layers "F.Cu" "F.Mask" "F.Paste")
			(net "HSC_VDD18")
		)
		(pad "2" smd circle
			(at 0.40005 0 180)
			(size 0 0)
			(layers "F.Cu" "F.Mask" "F.Paste")
			(net "AGND_HSC")
		)
	)
	(footprint ""
		(layer "F.Cu")
		(at 8.081772 -361.761278)
		(property "Reference" "H30"
			(at 2.3114 1.940052 0)
			(unlocked yes)
			(layer "F.SilkS")
			(effects
				(font
					(size 0.7874 0.5842)
					(thickness 0.1524)
				)
				(justify left)
			)
		)
		(property "Value" ""
			(at 0 0 0)
			(layer "F.Fab")
			(effects
				(font
					(size 1.27 1.27)
				)
			)
		)
		(duplicate_pad_numbers_are_jumpers no)
		(fp_circle
			(center 0 0)
			(end 2.4003 0)
			(stroke
				(width 0.1524)
				(type default)
			)
			(fill no)
			(layer "F.SilkS")
		)
		(fp_circle
			(center 0 0)
			(end 6.5913 0)
			(stroke
				(width 0.1524)
				(type default)
			)
			(fill no)
			(layer "B.SilkS")
		)
		(fp_circle
			(center 0 0)
			(end 6.5913 0)
			(stroke
				(width 0.1)
				(type default)
			)
			(fill no)
			(layer "B.Fab")
		)
		(fp_circle
			(center 0 0)
			(end 2.4003 0)
			(stroke
				(width 0.1)
				(type default)
			)
			(fill no)
			(layer "F.Fab")
		)
		(pad "" np_thru_hole circle
			(at 0 0)
			(size 3.175 3.175)
			(drill 3.175)
			(layers "*.Cu" "*.Mask")
			(clearance 0.381)
			(thermal_gap 0.381)
		)
		(zone
			(layers "F.Cu" "B.Cu" "In1.Cu" "In2.Cu" "In3.Cu" "In4.Cu" "In5.Cu" "In6.Cu"
				"In7.Cu" "In8.Cu" "In9.Cu" "In10.Cu" "In11.Cu" "In12.Cu" "In13.Cu" "In14.Cu"
				"In15.Cu" "In16.Cu"
			)
			(hatch none 0.5)
			(connect_pads
				(clearance 0)
			)
			(min_thickness 0.25)
			(keepout
				(tracks not_allowed)
				(vias allowed)
				(pads allowed)
				(copperpour not_allowed)
				(footprints allowed)
			)
			(placement
				(enabled no)
				(sheetname "")
			)
			(fill
				(thermal_gap 0.5)
				(thermal_bridge_width 0.5)
				(island_removal_mode 0)
			)
			(polygon
				(pts
					(arc
						(start 10.177272 -361.761278)
						(mid 5.986272 -361.761278)
						(end 10.177272 -361.761278)
					)
				)
			)
		)
	)
)
